# SCM (Grand Teton) — schematic netlist excerpt (pin names and nets, part order shuffled) for the footprints in the layout excerpt that follows; sources: Cadence DE-HDL packaged netlist, KiCad conversion of 12092022_DA0F0TMDCD0_F0T_Management_Board_D_brd_V3_OCP.brd

PR539  Q_RES  5.1 5% CHIP  pkg 0402LF  page 55 : A = PVCC1_AUX ; B = P1V2_AUX_VCC
R660  Q_RES  10K 1% EMPTY  pkg 0402LF  page 21 : A = P3V3_AUX ; B = EMMC_DT5_R

(kicad_pcb
	(version 20260206)
	(generator "pcbnew")
	(generator_version "10.0")
	(general
		(thickness 1.6)
		(legacy_teardrops no)
	)
	(paper "A4")
	(title_block
		(title "12092022_DA0F0TMDCD0_F0T_Management_Board_D_brd_V3_OCP.brd")
		(comment 1 "Grand Teton / footprints 169-170 of 1440")
	)
	(layers
		(0 "F.Cu" signal "TOP")
		(4 "In1.Cu" signal "GND")
		(6 "In2.Cu" signal "IN1")
		(8 "In3.Cu" signal "GND1")
		(10 "In4.Cu" signal "IN2")
		(12 "In5.Cu" signal "VCC")
		(14 "In6.Cu" signal "VCC1")
		(16 "In7.Cu" signal "IN3")
		(18 "In8.Cu" signal "GND2")
		(20 "In9.Cu" signal "IN4")
		(22 "In10.Cu" signal "GND3")
		(2 "B.Cu" signal "BOTTOM")
		(9 "F.Adhes" user "F.Adhesive")
		(11 "B.Adhes" user "B.Adhesive")
		(13 "F.Paste" user "Package Geometry/Pastemask Top")
		(15 "B.Paste" user "Package Geometry/Pastemask Bottom")
		(5 "F.SilkS" user "Ref Des/Silkscreen Top")
		(7 "B.SilkS" user "Ref Des/Silkscreen Bottom")
		(1 "F.Mask" user "Board Geometry/Soldermask Top")
		(3 "B.Mask" user "Board Geometry/Soldermask Bottom")
		(17 "Dwgs.User" user "User.Drawings")
		(19 "Cmts.User" user "User.Comments")
		(21 "Eco1.User" user "User.Eco1")
		(23 "Eco2.User" user "User.Eco2")
		(25 "Edge.Cuts" user "Board Geometry/Outline")
		(27 "Margin" user)
		(31 "F.CrtYd" user "Package Geometry/Place Bound Top")
		(29 "B.CrtYd" user "Package Geometry/Place Bound Bottom")
		(35 "F.Fab" user "Ref Des/Assembly Top")
		(33 "B.Fab" user "Ref Des/Assembly Bottom")
	)
	(footprint ""
		(layer "F.Cu")
		(at 31.56204 -70.536054 90)
		(property "Reference" "R660"
			(at 0 0 90)
			(layer "F.SilkS")
			(hide yes)
			(effects
				(font
					(size 1.27 1.27)
				)
			)
		)
		(property "Value" ""
			(at 0 0 90)
			(layer "F.Fab")
			(effects
				(font
					(size 1.27 1.27)
				)
			)
		)
		(duplicate_pad_numbers_are_jumpers no)
		(fp_line
			(start 0.7874 -0.4064)
			(end 0.7874 0.4064)
			(stroke
				(width 0.1524)
				(type default)
			)
			(layer "F.SilkS")
		)
		(fp_line
			(start -0.7874 -0.4064)
			(end 0.7874 -0.4064)
			(stroke
				(width 0.1524)
				(type default)
			)
			(layer "F.SilkS")
		)
		(fp_line
			(start 0.7874 0.4064)
			(end -0.7874 0.4064)
			(stroke
				(width 0.1524)
				(type default)
			)
			(layer "F.SilkS")
		)
		(fp_line
			(start -0.7874 0.4064)
			(end -0.7874 -0.4064)
			(stroke
				(width 0.1524)
				(type default)
			)
			(layer "F.SilkS")
		)
		(fp_line
			(start -0.12065 -0.305054)
			(end -0.12065 -0.2794)
			(stroke
				(width 0.1)
				(type default)
			)
			(layer "F.Fab")
		)
		(fp_line
			(start -0.67945 -0.305054)
			(end -0.12065 -0.305054)
			(stroke
				(width 0.1)
				(type default)
			)
			(layer "F.Fab")
		)
		(fp_line
			(start 0.67945 -0.3048)
			(end 0.67945 0.3048)
			(stroke
				(width 0.1)
				(type default)
			)
			(layer "F.Fab")
		)
		(fp_line
			(start 0.12065 -0.3048)
			(end 0.67945 -0.3048)
			(stroke
				(width 0.1)
				(type default)
			)
			(layer "F.Fab")
		)
		(fp_line
			(start 0.12065 -0.2794)
			(end 0.12065 -0.3048)
			(stroke
				(width 0.1)
				(type default)
			)
			(layer "F.Fab")
		)
		(fp_line
			(start -0.12065 -0.2794)
			(end 0.12065 -0.2794)
			(stroke
				(width 0.1)
				(type default)
			)
			(layer "F.Fab")
		)
		(fp_line
			(start 0.120396 0.2794)
			(end -0.12065 0.2794)
			(stroke
				(width 0.1)
				(type default)
			)
			(layer "F.Fab")
		)
		(fp_line
			(start -0.12065 0.2794)
			(end -0.12065 0.3048)
			(stroke
				(width 0.1)
				(type default)
			)
			(layer "F.Fab")
		)
		(fp_line
			(start 0.67945 0.3048)
			(end 0.120396 0.3048)
			(stroke
				(width 0.1)
				(type default)
			)
			(layer "F.Fab")
		)
		(fp_line
			(start 0.120396 0.3048)
			(end 0.120396 0.2794)
			(stroke
				(width 0.1)
				(type default)
			)
			(layer "F.Fab")
		)
		(fp_line
			(start -0.12065 0.3048)
			(end -0.67945 0.3048)
			(stroke
				(width 0.1)
				(type default)
			)
			(layer "F.Fab")
		)
		(fp_line
			(start -0.67945 0.3048)
			(end -0.67945 -0.305054)
			(stroke
				(width 0.1)
				(type default)
			)
			(layer "F.Fab")
		)
		(pad "1" smd circle
			(at -0.40005 0 90)
			(size 0 0)
			(layers "F.Cu" "F.Mask" "F.Paste")
			(net "P3V3_AUX")
		)
		(pad "2" smd circle
			(at 0.40005 0 90)
			(size 0 0)
			(layers "F.Cu" "F.Mask" "F.Paste")
			(net "EMMC_DT5_R")
		)
	)
	(footprint ""
		(layer "F.Cu")
		(at 84.795106 -70.458838 90)
		(property "Reference" "PR539"
			(at 0 0 90)
			(layer "F.SilkS")
			(hide yes)
			(effects
				(font
					(size 1.27 1.27)
				)
			)
		)
		(property "Value" ""
			(at 0 0 90)
			(layer "F.Fab")
			(effects
				(font
					(size 1.27 1.27)
				)
			)
		)
		(duplicate_pad_numbers_are_jumpers no)
		(fp_line
			(start 0.7874 -0.4064)
			(end 0.7874 0.4064)
			(stroke
				(width 0.1524)
				(type default)
			)
			(layer "F.SilkS")
		)
		(fp_line
			(start -0.7874 -0.4064)
			(end 0.7874 -0.4064)
			(stroke
				(width 0.1524)
				(type default)
			)
			(layer "F.SilkS")
		)
		(fp_line
			(start 0.7874 0.4064)
			(end -0.7874 0.4064)
			(stroke
				(width 0.1524)
				(type default)
			)
			(layer "F.SilkS")
		)
		(fp_line
			(start -0.7874 0.4064)
			(end -0.7874 -0.4064)
			(stroke
				(width 0.1524)
				(type default)
			)
			(layer "F.SilkS")
		)
		(fp_line
			(start -0.12065 -0.305054)
			(end -0.12065 -0.2794)
			(stroke
				(width 0.1)
				(type default)
			)
			(layer "F.Fab")
		)
		(fp_line
			(start -0.67945 -0.305054)
			(end -0.12065 -0.305054)
			(stroke
				(width 0.1)
				(type default)
			)
			(layer "F.Fab")
		)
		(fp_line
			(start 0.67945 -0.3048)
			(end 0.67945 0.3048)
			(stroke
				(width 0.1)
				(type default)
			)
			(layer "F.Fab")
		)
		(fp_line
			(start 0.12065 -0.3048)
			(end 0.67945 -0.3048)
			(stroke
				(width 0.1)
				(type default)
			)
			(layer "F.Fab")
		)
		(fp_line
			(start 0.12065 -0.2794)
			(end 0.12065 -0.3048)
			(stroke
				(width 0.1)
				(type default)
			)
			(layer "F.Fab")
		)
		(fp_line
			(start -0.12065 -0.2794)
			(end 0.12065 -0.2794)
			(stroke
				(width 0.1)
				(type default)
			)
			(layer "F.Fab")
		)
		(fp_line
			(start 0.120396 0.2794)
			(end -0.12065 0.2794)
			(stroke
				(width 0.1)
				(type default)
			)
			(layer "F.Fab")
		)
		(fp_line
			(start -0.12065 0.2794)
			(end -0.12065 0.3048)
			(stroke
				(width 0.1)
				(type default)
			)
			(layer "F.Fab")
		)
		(fp_line
			(start 0.67945 0.3048)
			(end 0.120396 0.3048)
			(stroke
				(width 0.1)
				(type default)
			)
			(layer "F.Fab")
		)
		(fp_line
			(start 0.120396 0.3048)
			(end 0.120396 0.2794)
			(stroke
				(width 0.1)
				(type default)
			)
			(layer "F.Fab")
		)
		(fp_line
			(start -0.12065 0.3048)
			(end -0.67945 0.3048)
			(stroke
				(width 0.1)
				(type default)
			)
			(layer "F.Fab")
		)
		(fp_line
			(start -0.67945 0.3048)
			(end -0.67945 -0.305054)
			(stroke
				(width 0.1)
				(type default)
			)
			(layer "F.Fab")
		)
		(pad "1" smd circle
			(at -0.40005 0 90)
			(size 0 0)
			(layers "F.Cu" "F.Mask" "F.Paste")
			(net "PVCC1_AUX")
		)
		(pad "2" smd circle
			(at 0.40005 0 90)
			(size 0 0)
			(layers "F.Cu" "F.Mask" "F.Paste")
			(net "P1V2_AUX_VCC")
		)
	)
)
